(kicad_pcb
	(version 20260206)
	(generator "pcbnew")
	(generator_version "10.0")
	(general
		(thickness 1.6)
		(legacy_teardrops no)
	)
	(paper "A4")
	(title_block
		(title "panther-plus-userver — 13130-1b_20150205.brd")
		(comment 1 "Honey Badger (Wiwynn) / footprints 1329-1334 of 1509")
	)
	(layers
		(0 "F.Cu" signal "TOP")
		(4 "In1.Cu" signal "L2")
		(6 "In2.Cu" signal "L3")
		(8 "In3.Cu" signal "L4")
		(10 "In4.Cu" signal "L5")
		(12 "In5.Cu" signal "L6")
		(14 "In6.Cu" signal "L7")
		(16 "In7.Cu" signal "L8")
		(18 "In8.Cu" signal "L9")
		(20 "In9.Cu" signal "L10")
		(22 "In10.Cu" signal "L11")
		(2 "B.Cu" signal "BOTTOM")
		(9 "F.Adhes" user "F.Adhesive")
		(11 "B.Adhes" user "B.Adhesive")
		(13 "F.Paste" user "Package Geometry/Pastemask Top")
		(15 "B.Paste" user "Package Geometry/Pastemask Bottom")
		(5 "F.SilkS" user "Ref Des/Silkscreen Top")
		(7 "B.SilkS" user "Ref Des/Silkscreen Bottom")
		(1 "F.Mask" user "Board Geometry/Soldermask Top")
		(3 "B.Mask" user "Board Geometry/Soldermask Bottom")
		(17 "Dwgs.User" user "User.Drawings")
		(19 "Cmts.User" user "User.Comments")
		(21 "Eco1.User" user "User.Eco1")
		(23 "Eco2.User" user "User.Eco2")
		(25 "Edge.Cuts" user "Board Geometry/Outline")
		(27 "Margin" user)
		(31 "F.CrtYd" user "Package Geometry/Place Bound Top")
		(29 "B.CrtYd" user "Package Geometry/Place Bound Bottom")
		(35 "F.Fab" user "Ref Des/Assembly Top")
		(33 "B.Fab" user "Ref Des/Assembly Bottom")
	)
	(footprint ""
		(layer "B.Cu")
		(at 67.056 -21.082 90)
		(property "Reference" "PR184"
			(at 0 0 90)
			(layer "B.SilkS")
			(hide yes)
			(effects
				(font
					(size 1.27 1.27)
				)
				(justify mirror)
			)
		)
		(property "Value" "118KR3B-GP"
			(at 0.0254 -2.0193 90)
			(unlocked yes)
			(layer "B.Fab")
			(hide yes)
			(effects
				(font
					(size 1.016 1.016)
					(thickness 0.1524)
				)
				(justify mirror)
			)
		)
		(property "Device Type" "R603H22"
			(at 0.0254 -3.5433 90)
			(unlocked yes)
			(layer "B.Fab")
			(hide yes)
			(effects
				(font
					(size 1.016 1.016)
					(thickness 0.1524)
				)
				(justify mirror)
			)
		)
		(duplicate_pad_numbers_are_jumpers no)
		(fp_line
			(start 0.2032 0)
			(end 0.4191 0)
			(stroke
				(width 0.2032)
				(type default)
			)
			(layer "B.SilkS")
		)
		(fp_line
			(start -0.4318 0)
			(end -0.2032 0)
			(stroke
				(width 0.2032)
				(type default)
			)
			(layer "B.SilkS")
		)
		(fp_rect
			(start 0.635 1.1811)
			(end -0.635 -1.1811)
			(stroke
				(width 0)
				(type default)
			)
			(fill no)
			(layer "B.CrtYd")
		)
		(fp_rect
			(start 0.635 1.1811)
			(end -0.635 -1.1811)
			(stroke
				(width 0)
				(type default)
			)
			(fill no)
			(layer "B.Fab")
		)
		(pad "1" smd custom
			(at 0 -0.6604 270)
			(size 0.19685 0.19685)
			(layers "B.Cu" "B.Mask" "B.Paste")
			(net "VR_FB_P1V8_STBY")
			(options
				(clearance outline)
				(anchor circle)
			)
			(primitives
				(gr_poly
					(pts
						(arc
							(start 0.508 0.2921)
							(mid 0.478242 0.363942)
							(end 0.4064 0.3937)
						)
						(arc
							(start -0.4064 0.3937)
							(mid -0.478242 0.363942)
							(end -0.508 0.2921)
						)
						(arc
							(start -0.508 -0.2921)
							(mid -0.478242 -0.363942)
							(end -0.4064 -0.3937)
						)
						(arc
							(start 0.4064 -0.3937)
							(mid 0.478242 -0.363942)
							(end 0.508 -0.2921)
						)
					)
					(width 0)
					(fill yes)
				)
			)
		)
		(pad "2" smd custom
			(at 0 0.6604 270)
			(size 0.19685 0.19685)
			(layers "B.Cu" "B.Mask" "B.Paste")
			(net "AGND_P1V8_STBY")
			(options
				(clearance outline)
				(anchor circle)
			)
			(primitives
				(gr_poly
					(pts
						(arc
							(start 0.508 0.2921)
							(mid 0.478242 0.363942)
							(end 0.4064 0.3937)
						)
						(arc
							(start -0.4064 0.3937)
							(mid -0.478242 0.363942)
							(end -0.508 0.2921)
						)
						(arc
							(start -0.508 -0.2921)
							(mid -0.478242 -0.363942)
							(end -0.4064 -0.3937)
						)
						(arc
							(start 0.4064 -0.3937)
							(mid 0.478242 -0.363942)
							(end 0.508 -0.2921)
						)
					)
					(width 0)
					(fill yes)
				)
			)
		)
	)
	(footprint ""
		(layer "B.Cu")
		(at 67.31 -16.637 90)
		(property "Reference" "PR181"
			(at 0 0 90)
			(layer "B.SilkS")
			(hide yes)
			(effects
				(font
					(size 1.27 1.27)
				)
				(justify mirror)
			)
		)
		(property "Value" "0R3J-6-GP"
			(at 0.0254 -2.0193 90)
			(unlocked yes)
			(layer "B.Fab")
			(hide yes)
			(effects
				(font
					(size 1.016 1.016)
					(thickness 0.1524)
				)
				(justify mirror)
			)
		)
		(property "Device Type" "R603H22"
			(at 0.0254 -3.5433 90)
			(unlocked yes)
			(layer "B.Fab")
			(hide yes)
			(effects
				(font
					(size 1.016 1.016)
					(thickness 0.1524)
				)
				(justify mirror)
			)
		)
		(duplicate_pad_numbers_are_jumpers no)
		(fp_line
			(start 0.2032 0)
			(end 0.4191 0)
			(stroke
				(width 0.2032)
				(type default)
			)
			(layer "B.SilkS")
		)
		(fp_line
			(start -0.4318 0)
			(end -0.2032 0)
			(stroke
				(width 0.2032)
				(type default)
			)
			(layer "B.SilkS")
		)
		(fp_rect
			(start 0.635 1.1811)
			(end -0.635 -1.1811)
			(stroke
				(width 0)
				(type default)
			)
			(fill no)
			(layer "B.CrtYd")
		)
		(fp_rect
			(start 0.635 1.1811)
			(end -0.635 -1.1811)
			(stroke
				(width 0)
				(type default)
			)
			(fill no)
			(layer "B.Fab")
		)
		(pad "1" smd custom
			(at 0 -0.6604 270)
			(size 0.19685 0.19685)
			(layers "B.Cu" "B.Mask" "B.Paste")
			(net "P1V8_STBY")
			(options
				(clearance outline)
				(anchor circle)
			)
			(primitives
				(gr_poly
					(pts
						(arc
							(start 0.508 0.2921)
							(mid 0.478242 0.363942)
							(end 0.4064 0.3937)
						)
						(arc
							(start -0.4064 0.3937)
							(mid -0.478242 0.363942)
							(end -0.508 0.2921)
						)
						(arc
							(start -0.508 -0.2921)
							(mid -0.478242 -0.363942)
							(end -0.4064 -0.3937)
						)
						(arc
							(start 0.4064 -0.3937)
							(mid 0.478242 -0.363942)
							(end 0.508 -0.2921)
						)
					)
					(width 0)
					(fill yes)
				)
			)
		)
		(pad "2" smd custom
			(at 0 0.6604 270)
			(size 0.19685 0.19685)
			(layers "B.Cu" "B.Mask" "B.Paste")
			(net "P1V8_STBY_VOUT")
			(options
				(clearance outline)
				(anchor circle)
			)
			(primitives
				(gr_poly
					(pts
						(arc
							(start 0.508 0.2921)
							(mid 0.478242 0.363942)
							(end 0.4064 0.3937)
						)
						(arc
							(start -0.4064 0.3937)
							(mid -0.478242 0.363942)
							(end -0.508 0.2921)
						)
						(arc
							(start -0.508 -0.2921)
							(mid -0.478242 -0.363942)
							(end -0.4064 -0.3937)
						)
						(arc
							(start 0.4064 -0.3937)
							(mid 0.478242 -0.363942)
							(end 0.508 -0.2921)
						)
					)
					(width 0)
					(fill yes)
				)
			)
		)
	)
	(footprint ""
		(layer "B.Cu")
		(at 195.2498 -37.338 180)
		(property "Reference" "PQ3"
			(at 0 0 0)
			(layer "B.SilkS")
			(hide yes)
			(effects
				(font
					(size 1.27 1.27)
				)
				(justify mirror)
			)
		)
		(property "Value" "MMBT3904TT1G-GP"
			(at 2.032 -3.674618 180)
			(unlocked yes)
			(layer "B.Fab")
			(hide yes)
			(effects
				(font
					(size 1.016 1.016)
					(thickness 0.1524)
				)
				(justify mirror)
			)
		)
		(property "Device Type" "SC75CBE1D6H36"
			(at 2.032 -5.198618 180)
			(unlocked yes)
			(layer "B.Fab")
			(hide yes)
			(effects
				(font
					(size 1.016 1.016)
					(thickness 0.1524)
				)
				(justify mirror)
			)
		)
		(duplicate_pad_numbers_are_jumpers no)
		(fp_poly
			(pts
				(xy -0.381 -1.1938) (xy 0.381 -1.1938) (xy 0.381 -0.6604) (xy 1.0541 -0.6604) (xy 1.0541 0.6604)
				(xy 0.889 0.6604) (xy 0.889 1.1938) (xy -0.889 1.1938) (xy -0.889 0.6604) (xy -1.0541 0.6604) (xy -1.0541 -0.6604)
				(xy -0.381 -0.6604)
			)
			(stroke
				(width 0)
				(type default)
			)
			(fill no)
			(layer "B.CrtYd")
		)
		(fp_poly
			(pts
				(xy -0.381 -1.1938) (xy 0.381 -1.1938) (xy 0.381 -0.6604) (xy 1.0541 -0.6604) (xy 1.0541 0.6604)
				(xy 0.889 0.6604) (xy 0.889 1.1938) (xy -0.889 1.1938) (xy -0.889 0.6604) (xy -1.0541 0.6604) (xy -1.0541 -0.6604)
				(xy -0.381 -0.6604)
			)
			(stroke
				(width 0)
				(type default)
			)
			(fill no)
			(layer "B.Fab")
		)
		(pad "B" smd custom
			(at 0.508 0.6604)
			(size 0.127 0.127)
			(layers "B.Cu" "B.Mask" "B.Paste")
			(net "VDDR_Z")
			(options
				(clearance outline)
				(anchor circle)
			)
			(primitives
				(gr_poly
					(pts
						(arc
							(start -0.0508 -0.4064)
							(mid -0.194484 -0.346884)
							(end -0.254 -0.2032)
						)
						(arc
							(start -0.254 0.2032)
							(mid -0.194484 0.346884)
							(end -0.0508 0.4064)
						)
						(arc
							(start 0.0508 0.4064)
							(mid 0.194484 0.346884)
							(end 0.254 0.2032)
						)
						(arc
							(start 0.254 -0.2032)
							(mid 0.194484 -0.346884)
							(end 0.0508 -0.4064)
						)
					)
					(width 0)
					(fill yes)
				)
			)
		)
		(pad "C" smd custom
			(at 0 -0.6604)
			(size 0.127 0.127)
			(layers "B.Cu" "B.Mask" "B.Paste")
			(net "P12V")
			(options
				(clearance outline)
				(anchor circle)
			)
			(primitives
				(gr_poly
					(pts
						(arc
							(start -0.0508 -0.4064)
							(mid -0.194484 -0.346884)
							(end -0.254 -0.2032)
						)
						(arc
							(start -0.254 0.2032)
							(mid -0.194484 0.346884)
							(end -0.0508 0.4064)
						)
						(arc
							(start 0.0508 0.4064)
							(mid 0.194484 0.346884)
							(end 0.254 0.2032)
						)
						(arc
							(start 0.254 -0.2032)
							(mid 0.194484 -0.346884)
							(end 0.0508 -0.4064)
						)
					)
					(width 0)
					(fill yes)
				)
			)
		)
		(pad "E" smd custom
			(at -0.508 0.6604)
			(size 0.127 0.127)
			(layers "B.Cu" "B.Mask" "B.Paste")
			(net "VDDR_5VBIAS")
			(options
				(clearance outline)
				(anchor circle)
			)
			(primitives
				(gr_poly
					(pts
						(arc
							(start -0.0508 -0.4064)
							(mid -0.194484 -0.346884)
							(end -0.254 -0.2032)
						)
						(arc
							(start -0.254 0.2032)
							(mid -0.194484 0.346884)
							(end -0.0508 0.4064)
						)
						(arc
							(start 0.0508 0.4064)
							(mid 0.194484 0.346884)
							(end 0.254 0.2032)
						)
						(arc
							(start 0.254 -0.2032)
							(mid 0.194484 -0.346884)
							(end 0.0508 -0.4064)
						)
					)
					(width 0)
					(fill yes)
				)
			)
		)
	)
	(footprint ""
		(layer "B.Cu")
		(at 186.6392 -27.6098 90)
		(property "Reference" "C75"
			(at 0 0 90)
			(layer "B.SilkS")
			(hide yes)
			(effects
				(font
					(size 1.27 1.27)
				)
				(justify mirror)
			)
		)
		(property "Value" "SCD22U16V2KX-GP"
			(at -1.8923 -1.2065 90)
			(unlocked yes)
			(layer "B.Fab")
			(hide yes)
			(effects
				(font
					(size 1.016 1.016)
					(thickness 0.1524)
				)
				(justify mirror)
			)
		)
		(property "Device Type" "C402H22"
			(at -1.8923 -2.7305 90)
			(unlocked yes)
			(layer "B.Fab")
			(hide yes)
			(effects
				(font
					(size 1.016 1.016)
					(thickness 0.1524)
				)
				(justify mirror)
			)
		)
		(duplicate_pad_numbers_are_jumpers no)
		(fp_rect
			(start 0.381 0.7366)
			(end -0.381 -0.7366)
			(stroke
				(width 0)
				(type default)
			)
			(fill no)
			(layer "B.CrtYd")
		)
		(fp_rect
			(start 0.381 0.7366)
			(end -0.381 -0.7366)
			(stroke
				(width 0)
				(type default)
			)
			(fill no)
			(layer "B.Fab")
		)
		(pad "1" smd custom
			(at 0 -0.4572 270)
			(size 0.1143 0.1143)
			(layers "B.Cu" "B.Mask" "B.Paste")
			(net "VR_PVDDRA_ISUMP1")
			(options
				(clearance outline)
				(anchor circle)
			)
			(primitives
				(gr_poly
					(pts
						(arc
							(start -0.254 0.1778)
							(mid -0.239121 0.213721)
							(end -0.2032 0.2286)
						)
						(arc
							(start 0.2032 0.2286)
							(mid 0.239121 0.213721)
							(end 0.254 0.1778)
						)
						(arc
							(start 0.254 -0.1778)
							(mid 0.239121 -0.213721)
							(end 0.2032 -0.2286)
						)
						(arc
							(start -0.2032 -0.2286)
							(mid -0.239121 -0.213721)
							(end -0.254 -0.1778)
						)
					)
					(width 0)
					(fill yes)
				)
			)
		)
		(pad "2" smd custom
			(at 0 0.4572 270)
			(size 0.1143 0.1143)
			(layers "B.Cu" "B.Mask" "B.Paste")
			(net "VR_PVDDRA_ISUMN1")
			(options
				(clearance outline)
				(anchor circle)
			)
			(primitives
				(gr_poly
					(pts
						(arc
							(start -0.254 0.1778)
							(mid -0.239121 0.213721)
							(end -0.2032 0.2286)
						)
						(arc
							(start 0.2032 0.2286)
							(mid 0.239121 0.213721)
							(end 0.254 0.1778)
						)
						(arc
							(start 0.254 -0.1778)
							(mid 0.239121 -0.213721)
							(end 0.2032 -0.2286)
						)
						(arc
							(start -0.2032 -0.2286)
							(mid -0.239121 -0.213721)
							(end -0.254 -0.1778)
						)
					)
					(width 0)
					(fill yes)
				)
			)
		)
	)
	(footprint ""
		(layer "B.Cu")
		(at 36.957 -28.448 90)
		(property "Reference" "R449"
			(at 0 0 90)
			(layer "B.SilkS")
			(hide yes)
			(effects
				(font
					(size 1.27 1.27)
				)
				(justify mirror)
			)
		)
		(property "Value" "4K7R2F-GP"
			(at -1.7907 -1.1176 90)
			(unlocked yes)
			(layer "B.Fab")
			(hide yes)
			(effects
				(font
					(size 1.016 1.016)
					(thickness 0.1524)
				)
				(justify mirror)
			)
		)
		(property "Device Type" "R402H16"
			(at -1.7907 -2.6416 90)
			(unlocked yes)
			(layer "B.Fab")
			(hide yes)
			(effects
				(font
					(size 1.016 1.016)
					(thickness 0.1524)
				)
				(justify mirror)
			)
		)
		(duplicate_pad_numbers_are_jumpers no)
		(fp_rect
			(start 0.381 0.8382)
			(end -0.381 -0.8382)
			(stroke
				(width 0)
				(type default)
			)
			(fill no)
			(layer "B.CrtYd")
		)
		(fp_rect
			(start 0.381 0.8382)
			(end -0.381 -0.8382)
			(stroke
				(width 0)
				(type default)
			)
			(fill no)
			(layer "B.Fab")
		)
		(pad "1" smd custom
			(at 0 -0.4318 270)
			(size 0.127 0.127)
			(layers "B.Cu" "B.Mask" "B.Paste")
			(net "P3V3")
			(options
				(clearance outline)
				(anchor circle)
			)
			(primitives
				(gr_poly
					(pts
						(arc
							(start -0.2032 0.2794)
							(mid -0.239121 0.264521)
							(end -0.254 0.2286)
						)
						(arc
							(start -0.254 -0.2286)
							(mid -0.239121 -0.264521)
							(end -0.2032 -0.2794)
						)
						(arc
							(start 0.2032 -0.2794)
							(mid 0.239121 -0.264521)
							(end 0.254 -0.2286)
						)
						(arc
							(start 0.254 0.2286)
							(mid 0.239121 0.264521)
							(end 0.2032 0.2794)
						)
					)
					(width 0)
					(fill yes)
				)
			)
		)
		(pad "2" smd custom
			(at 0 0.4318 270)
			(size 0.127 0.127)
			(layers "B.Cu" "B.Mask" "B.Paste")
			(net "CLKCUFF_SMB_ADDR")
			(options
				(clearance outline)
				(anchor circle)
			)
			(primitives
				(gr_poly
					(pts
						(arc
							(start -0.2032 0.2794)
							(mid -0.239121 0.264521)
							(end -0.254 0.2286)
						)
						(arc
							(start -0.254 -0.2286)
							(mid -0.239121 -0.264521)
							(end -0.2032 -0.2794)
						)
						(arc
							(start 0.2032 -0.2794)
							(mid 0.239121 -0.264521)
							(end 0.254 -0.2286)
						)
						(arc
							(start 0.254 0.2286)
							(mid 0.239121 0.264521)
							(end 0.2032 0.2794)
						)
					)
					(width 0)
					(fill yes)
				)
			)
		)
	)
	(footprint ""
		(layer "B.Cu")
		(at 144.4244 -48.26 -90)
		(property "Reference" "R80"
			(at 0 0 90)
			(layer "B.SilkS")
			(hide yes)
			(effects
				(font
					(size 1.27 1.27)
				)
				(justify mirror)
			)
		)
		(property "Value" "1KR2F-3-GP"
			(at -0.064008 -3.993896 270)
			(unlocked yes)
			(layer "B.Fab")
			(hide yes)
			(effects
				(font
					(size 1.016 1.016)
					(thickness 0.1524)
				)
				(justify mirror)
			)
		)
		(property "Device Type" "R402H16"
			(at -0.064008 -5.517896 270)
			(unlocked yes)
			(layer "B.Fab")
			(hide yes)
			(effects
				(font
					(size 1.016 1.016)
					(thickness 0.1524)
				)
				(justify mirror)
			)
		)
		(duplicate_pad_numbers_are_jumpers no)
		(fp_rect
			(start 0.381 0.8382)
			(end -0.381 -0.8382)
			(stroke
				(width 0)
				(type default)
			)
			(fill no)
			(layer "B.CrtYd")
		)
		(fp_rect
			(start 0.381 0.8382)
			(end -0.381 -0.8382)
			(stroke
				(width 0)
				(type default)
			)
			(fill no)
			(layer "B.Fab")
		)
		(pad "1" smd custom
			(at 0 -0.4318 90)
			(size 0.127 0.127)
			(layers "B.Cu" "B.Mask" "B.Paste")
			(net "C_DCLK")
			(options
				(clearance outline)
				(anchor circle)
			)
			(primitives
				(gr_poly
					(pts
						(arc
							(start -0.2032 0.2794)
							(mid -0.239121 0.264521)
							(end -0.254 0.2286)
						)
						(arc
							(start -0.254 -0.2286)
							(mid -0.239121 -0.264521)
							(end -0.2032 -0.2794)
						)
						(arc
							(start 0.2032 -0.2794)
							(mid 0.239121 -0.264521)
							(end 0.254 -0.2286)
						)
						(arc
							(start 0.254 0.2286)
							(mid 0.239121 0.264521)
							(end 0.2032 0.2794)
						)
					)
					(width 0)
					(fill yes)
				)
			)
		)
		(pad "2" smd custom
			(at 0 0.4318 90)
			(size 0.127 0.127)
			(layers "B.Cu" "B.Mask" "B.Paste")
			(net "P3V3_STBY")
			(options
				(clearance outline)
				(anchor circle)
			)
			(primitives
				(gr_poly
					(pts
						(arc
							(start -0.2032 0.2794)
							(mid -0.239121 0.264521)
							(end -0.254 0.2286)
						)
						(arc
							(start -0.254 -0.2286)
							(mid -0.239121 -0.264521)
							(end -0.2032 -0.2794)
						)
						(arc
							(start 0.2032 -0.2794)
							(mid 0.239121 -0.264521)
							(end 0.254 -0.2286)
						)
						(arc
							(start 0.254 0.2286)
							(mid 0.239121 0.264521)
							(end 0.2032 0.2794)
						)
					)
					(width 0)
					(fill yes)
				)
			)
		)
	)
)
